;LEADER: 12 
;HEADER: 
;CODE  : ASCII 
;FILE  : 9332_F0TG_MB_C_V02_0417_0820-bd-1-15.drl for backdrilling ... from layer TOP to layer GND6
;DESIGN: 9332_F0TG_MB_C_V02_0417_0820.brd
;MUST-NOT-CUT-LAYER = IN6,  MAX_DRILL_DEPTH = 83.60 MILS,  MFG_STUB_LENGTH = 0.00 MILS
;   BackdrillSize 1. = 17.000000 Tolerance = +0.000000/-0.000000 NON_PLATED MILS Quantity = 8
%
G90
X1436263Y0008289
X1245840Y0008289
X1436263Y0011689
X1245840Y0011689
X1177404Y-0008311
X0842320Y-0008311
X1177404Y-0011711
X0842320Y-0011711
M30
